(kicad_pcb
	(version 20260206)
	(generator "pcbnew")
	(generator_version "10.0")
	(general
		(thickness 1.6)
		(legacy_teardrops no)
	)
	(paper "A4")
	(title_block
		(title "12092022_DA0F0TFB6D0_F0T_FAN_BOARD_MP5048_D_brd_v02_OCP.brd")
		(comment 1 "Grand Teton / footprints 31-36 of 924")
	)
	(layers
		(0 "F.Cu" signal "TOP")
		(4 "In1.Cu" signal "GND")
		(6 "In2.Cu" signal "IN1")
		(8 "In3.Cu" signal "IN2")
		(10 "In4.Cu" signal "GND1")
		(2 "B.Cu" signal "BOTTOM")
		(9 "F.Adhes" user "F.Adhesive")
		(11 "B.Adhes" user "B.Adhesive")
		(13 "F.Paste" user "Package Geometry/Pastemask Top")
		(15 "B.Paste" user "Package Geometry/Pastemask Bottom")
		(5 "F.SilkS" user "Ref Des/Silkscreen Top")
		(7 "B.SilkS" user "Ref Des/Silkscreen Bottom")
		(1 "F.Mask" user "Board Geometry/Soldermask Top")
		(3 "B.Mask" user "Board Geometry/Soldermask Bottom")
		(17 "Dwgs.User" user "User.Drawings")
		(19 "Cmts.User" user "User.Comments")
		(21 "Eco1.User" user "User.Eco1")
		(23 "Eco2.User" user "User.Eco2")
		(25 "Edge.Cuts" user "Board Geometry/Outline")
		(27 "Margin" user)
		(31 "F.CrtYd" user "Package Geometry/Place Bound Top")
		(29 "B.CrtYd" user "Package Geometry/Place Bound Bottom")
		(35 "F.Fab" user "Ref Des/Assembly Top")
		(33 "B.Fab" user "Ref Des/Assembly Bottom")
	)
	(footprint ""
		(layer "F.Cu")
		(at 22.225 -136.017 -90)
		(property "Reference" "R4951"
			(at 0 0 270)
			(layer "F.SilkS")
			(hide yes)
			(effects
				(font
					(size 1.27 1.27)
				)
			)
		)
		(property "Value" ""
			(at 0 0 270)
			(layer "F.Fab")
			(effects
				(font
					(size 1.27 1.27)
				)
			)
		)
		(duplicate_pad_numbers_are_jumpers no)
		(fp_line
			(start -0.7874 0.4064)
			(end -0.7874 -0.4064)
			(stroke
				(width 0.1524)
				(type default)
			)
			(layer "F.SilkS")
		)
		(fp_line
			(start 0.7874 0.4064)
			(end -0.7874 0.4064)
			(stroke
				(width 0.1524)
				(type default)
			)
			(layer "F.SilkS")
		)
		(fp_line
			(start -0.7874 -0.4064)
			(end 0.7874 -0.4064)
			(stroke
				(width 0.1524)
				(type default)
			)
			(layer "F.SilkS")
		)
		(fp_line
			(start 0.7874 -0.4064)
			(end 0.7874 0.4064)
			(stroke
				(width 0.1524)
				(type default)
			)
			(layer "F.SilkS")
		)
		(fp_line
			(start -0.67945 0.3048)
			(end -0.67945 -0.305054)
			(stroke
				(width 0.1)
				(type default)
			)
			(layer "F.Fab")
		)
		(fp_line
			(start -0.12065 0.3048)
			(end -0.67945 0.3048)
			(stroke
				(width 0.1)
				(type default)
			)
			(layer "F.Fab")
		)
		(fp_line
			(start 0.120396 0.3048)
			(end 0.120396 0.2794)
			(stroke
				(width 0.1)
				(type default)
			)
			(layer "F.Fab")
		)
		(fp_line
			(start 0.67945 0.3048)
			(end 0.120396 0.3048)
			(stroke
				(width 0.1)
				(type default)
			)
			(layer "F.Fab")
		)
		(fp_line
			(start -0.12065 0.2794)
			(end -0.12065 0.3048)
			(stroke
				(width 0.1)
				(type default)
			)
			(layer "F.Fab")
		)
		(fp_line
			(start 0.120396 0.2794)
			(end -0.12065 0.2794)
			(stroke
				(width 0.1)
				(type default)
			)
			(layer "F.Fab")
		)
		(fp_line
			(start -0.12065 -0.2794)
			(end 0.12065 -0.2794)
			(stroke
				(width 0.1)
				(type default)
			)
			(layer "F.Fab")
		)
		(fp_line
			(start 0.12065 -0.2794)
			(end 0.12065 -0.3048)
			(stroke
				(width 0.1)
				(type default)
			)
			(layer "F.Fab")
		)
		(fp_line
			(start 0.12065 -0.3048)
			(end 0.67945 -0.3048)
			(stroke
				(width 0.1)
				(type default)
			)
			(layer "F.Fab")
		)
		(fp_line
			(start 0.67945 -0.3048)
			(end 0.67945 0.3048)
			(stroke
				(width 0.1)
				(type default)
			)
			(layer "F.Fab")
		)
		(fp_line
			(start -0.67945 -0.305054)
			(end -0.12065 -0.305054)
			(stroke
				(width 0.1)
				(type default)
			)
			(layer "F.Fab")
		)
		(fp_line
			(start -0.12065 -0.305054)
			(end -0.12065 -0.2794)
			(stroke
				(width 0.1)
				(type default)
			)
			(layer "F.Fab")
		)
		(pad "1" smd circle
			(at -0.40005 0 270)
			(size 0 0)
			(layers "F.Cu" "F.Mask" "F.Paste")
			(net "GND")
		)
		(pad "2" smd circle
			(at 0.40005 0 270)
			(size 0 0)
			(layers "F.Cu" "F.Mask" "F.Paste")
			(net "MAX31790_U330_SPIN_START")
		)
	)
	(footprint ""
		(layer "F.Cu")
		(at 39.206932 -70.542912 180)
		(property "Reference" "R5421"
			(at 0 0 180)
			(layer "F.SilkS")
			(hide yes)
			(effects
				(font
					(size 1.27 1.27)
				)
			)
		)
		(property "Value" ""
			(at 0 0 180)
			(layer "F.Fab")
			(effects
				(font
					(size 1.27 1.27)
				)
			)
		)
		(duplicate_pad_numbers_are_jumpers no)
		(fp_line
			(start 0.7874 0.4064)
			(end -0.7874 0.4064)
			(stroke
				(width 0.1524)
				(type default)
			)
			(layer "F.SilkS")
		)
		(fp_line
			(start 0.7874 -0.4064)
			(end 0.7874 0.4064)
			(stroke
				(width 0.1524)
				(type default)
			)
			(layer "F.SilkS")
		)
		(fp_line
			(start -0.7874 0.4064)
			(end -0.7874 -0.4064)
			(stroke
				(width 0.1524)
				(type default)
			)
			(layer "F.SilkS")
		)
		(fp_line
			(start -0.7874 -0.4064)
			(end 0.7874 -0.4064)
			(stroke
				(width 0.1524)
				(type default)
			)
			(layer "F.SilkS")
		)
		(fp_line
			(start 0.67945 0.3048)
			(end 0.120396 0.3048)
			(stroke
				(width 0.1)
				(type default)
			)
			(layer "F.Fab")
		)
		(fp_line
			(start 0.67945 -0.3048)
			(end 0.67945 0.3048)
			(stroke
				(width 0.1)
				(type default)
			)
			(layer "F.Fab")
		)
		(fp_line
			(start 0.12065 -0.2794)
			(end 0.12065 -0.3048)
			(stroke
				(width 0.1)
				(type default)
			)
			(layer "F.Fab")
		)
		(fp_line
			(start 0.12065 -0.3048)
			(end 0.67945 -0.3048)
			(stroke
				(width 0.1)
				(type default)
			)
			(layer "F.Fab")
		)
		(fp_line
			(start 0.120396 0.3048)
			(end 0.120396 0.2794)
			(stroke
				(width 0.1)
				(type default)
			)
			(layer "F.Fab")
		)
		(fp_line
			(start 0.120396 0.2794)
			(end -0.12065 0.2794)
			(stroke
				(width 0.1)
				(type default)
			)
			(layer "F.Fab")
		)
		(fp_line
			(start -0.12065 0.3048)
			(end -0.67945 0.3048)
			(stroke
				(width 0.1)
				(type default)
			)
			(layer "F.Fab")
		)
		(fp_line
			(start -0.12065 0.2794)
			(end -0.12065 0.3048)
			(stroke
				(width 0.1)
				(type default)
			)
			(layer "F.Fab")
		)
		(fp_line
			(start -0.12065 -0.2794)
			(end 0.12065 -0.2794)
			(stroke
				(width 0.1)
				(type default)
			)
			(layer "F.Fab")
		)
		(fp_line
			(start -0.12065 -0.305054)
			(end -0.12065 -0.2794)
			(stroke
				(width 0.1)
				(type default)
			)
			(layer "F.Fab")
		)
		(fp_line
			(start -0.67945 0.3048)
			(end -0.67945 -0.305054)
			(stroke
				(width 0.1)
				(type default)
			)
			(layer "F.Fab")
		)
		(fp_line
			(start -0.67945 -0.305054)
			(end -0.12065 -0.305054)
			(stroke
				(width 0.1)
				(type default)
			)
			(layer "F.Fab")
		)
		(pad "1" smd circle
			(at -0.40005 0 180)
			(size 0 0)
			(layers "F.Cu" "F.Mask" "F.Paste")
			(net "FAN_2_ON")
		)
		(pad "2" smd circle
			(at 0.40005 0 180)
			(size 0 0)
			(layers "F.Cu" "F.Mask" "F.Paste")
			(net "P52V_FAN_2_EN")
		)
	)
	(footprint ""
		(layer "F.Cu")
		(at 14.351 -200.180956 180)
		(property "Reference" "R5223"
			(at 0 0 180)
			(layer "F.SilkS")
			(hide yes)
			(effects
				(font
					(size 1.27 1.27)
				)
			)
		)
		(property "Value" ""
			(at 0 0 180)
			(layer "F.Fab")
			(effects
				(font
					(size 1.27 1.27)
				)
			)
		)
		(duplicate_pad_numbers_are_jumpers no)
		(fp_line
			(start 0.7874 0.4064)
			(end -0.7874 0.4064)
			(stroke
				(width 0.1524)
				(type default)
			)
			(layer "F.SilkS")
		)
		(fp_line
			(start 0.7874 -0.4064)
			(end 0.7874 0.4064)
			(stroke
				(width 0.1524)
				(type default)
			)
			(layer "F.SilkS")
		)
		(fp_line
			(start -0.7874 0.4064)
			(end -0.7874 -0.4064)
			(stroke
				(width 0.1524)
				(type default)
			)
			(layer "F.SilkS")
		)
		(fp_line
			(start -0.7874 -0.4064)
			(end 0.7874 -0.4064)
			(stroke
				(width 0.1524)
				(type default)
			)
			(layer "F.SilkS")
		)
		(fp_line
			(start 0.67945 0.3048)
			(end 0.120396 0.3048)
			(stroke
				(width 0.1)
				(type default)
			)
			(layer "F.Fab")
		)
		(fp_line
			(start 0.67945 -0.3048)
			(end 0.67945 0.3048)
			(stroke
				(width 0.1)
				(type default)
			)
			(layer "F.Fab")
		)
		(fp_line
			(start 0.12065 -0.2794)
			(end 0.12065 -0.3048)
			(stroke
				(width 0.1)
				(type default)
			)
			(layer "F.Fab")
		)
		(fp_line
			(start 0.12065 -0.3048)
			(end 0.67945 -0.3048)
			(stroke
				(width 0.1)
				(type default)
			)
			(layer "F.Fab")
		)
		(fp_line
			(start 0.120396 0.3048)
			(end 0.120396 0.2794)
			(stroke
				(width 0.1)
				(type default)
			)
			(layer "F.Fab")
		)
		(fp_line
			(start 0.120396 0.2794)
			(end -0.12065 0.2794)
			(stroke
				(width 0.1)
				(type default)
			)
			(layer "F.Fab")
		)
		(fp_line
			(start -0.12065 0.3048)
			(end -0.67945 0.3048)
			(stroke
				(width 0.1)
				(type default)
			)
			(layer "F.Fab")
		)
		(fp_line
			(start -0.12065 0.2794)
			(end -0.12065 0.3048)
			(stroke
				(width 0.1)
				(type default)
			)
			(layer "F.Fab")
		)
		(fp_line
			(start -0.12065 -0.2794)
			(end 0.12065 -0.2794)
			(stroke
				(width 0.1)
				(type default)
			)
			(layer "F.Fab")
		)
		(fp_line
			(start -0.12065 -0.305054)
			(end -0.12065 -0.2794)
			(stroke
				(width 0.1)
				(type default)
			)
			(layer "F.Fab")
		)
		(fp_line
			(start -0.67945 0.3048)
			(end -0.67945 -0.305054)
			(stroke
				(width 0.1)
				(type default)
			)
			(layer "F.Fab")
		)
		(fp_line
			(start -0.67945 -0.305054)
			(end -0.12065 -0.305054)
			(stroke
				(width 0.1)
				(type default)
			)
			(layer "F.Fab")
		)
		(pad "1" smd circle
			(at -0.40005 0 180)
			(size 0 0)
			(layers "F.Cu" "F.Mask" "F.Paste")
			(net "SMB_FAN6_SCL")
		)
		(pad "2" smd circle
			(at 0.40005 0 180)
			(size 0 0)
			(layers "F.Cu" "F.Mask" "F.Paste")
			(net "SMB_FAN6_SCL_R")
		)
	)
	(footprint ""
		(layer "F.Cu")
		(at 36.322 -302.26)
		(property "Reference" "D131"
			(at 2.20472 -1.04775 0)
			(unlocked yes)
			(layer "F.SilkS")
			(effects
				(font
					(size 0.7874 0.5842)
					(thickness 0.1524)
				)
				(justify left)
			)
		)
		(property "Value" ""
			(at 0 0 0)
			(layer "F.Fab")
			(effects
				(font
					(size 1.27 1.27)
				)
			)
		)
		(duplicate_pad_numbers_are_jumpers no)
		(fp_line
			(start -0.299974 -0.500126)
			(end -0.299974 0.500126)
			(stroke
				(width 0.1524)
				(type default)
			)
			(layer "F.SilkS")
		)
		(fp_line
			(start -0.299974 0.500126)
			(end 0.199898 0)
			(stroke
				(width 0.1524)
				(type default)
			)
			(layer "F.SilkS")
		)
		(fp_line
			(start 0.199898 0)
			(end -0.299974 -0.500126)
			(stroke
				(width 0.1524)
				(type default)
			)
			(layer "F.SilkS")
		)
		(fp_line
			(start 0.299974 -0.500126)
			(end 0.299974 0.500126)
			(stroke
				(width 0.1524)
				(type default)
			)
			(layer "F.SilkS")
		)
		(fp_line
			(start 1.651 -0.6858)
			(end 1.651 0.6858)
			(stroke
				(width 0.1524)
				(type default)
			)
			(layer "F.SilkS")
		)
		(fp_line
			(start 1.778 0.6858)
			(end 1.778 -0.6858)
			(stroke
				(width 0.1524)
				(type default)
			)
			(layer "F.SilkS")
		)
		(fp_line
			(start -1.35001 -0.225044)
			(end -0.899922 -0.225044)
			(stroke
				(width 0.1)
				(type default)
			)
			(layer "F.Fab")
		)
		(fp_line
			(start -1.35001 0.175006)
			(end -1.35001 -0.225044)
			(stroke
				(width 0.1)
				(type default)
			)
			(layer "F.Fab")
		)
		(fp_line
			(start -0.899922 -0.700024)
			(end 0.899922 -0.700024)
			(stroke
				(width 0.1)
				(type default)
			)
			(layer "F.Fab")
		)
		(fp_line
			(start -0.899922 -0.225044)
			(end -0.899922 -0.700024)
			(stroke
				(width 0.1)
				(type default)
			)
			(layer "F.Fab")
		)
		(fp_line
			(start -0.899922 0.175006)
			(end -1.35001 0.175006)
			(stroke
				(width 0.1)
				(type default)
			)
			(layer "F.Fab")
		)
		(fp_line
			(start -0.899922 0.700024)
			(end -0.899922 0.175006)
			(stroke
				(width 0.1)
				(type default)
			)
			(layer "F.Fab")
		)
		(fp_line
			(start -0.299974 -0.500126)
			(end -0.299974 0.500126)
			(stroke
				(width 0.1)
				(type default)
			)
			(layer "F.Fab")
		)
		(fp_line
			(start -0.299974 0.500126)
			(end 0.199898 0)
			(stroke
				(width 0.1)
				(type default)
			)
			(layer "F.Fab")
		)
		(fp_line
			(start 0.199898 0)
			(end -0.299974 -0.500126)
			(stroke
				(width 0.1)
				(type default)
			)
			(layer "F.Fab")
		)
		(fp_line
			(start 0.299974 -0.500126)
			(end 0.299974 0.500126)
			(stroke
				(width 0.1)
				(type default)
			)
			(layer "F.Fab")
		)
		(fp_line
			(start 0.899922 -0.700024)
			(end 0.899922 -0.225044)
			(stroke
				(width 0.1)
				(type default)
			)
			(layer "F.Fab")
		)
		(fp_line
			(start 0.899922 -0.225044)
			(end 1.35001 -0.225044)
			(stroke
				(width 0.1)
				(type default)
			)
			(layer "F.Fab")
		)
		(fp_line
			(start 0.899922 0.175006)
			(end 0.899922 0.700024)
			(stroke
				(width 0.1)
				(type default)
			)
			(layer "F.Fab")
		)
		(fp_line
			(start 0.899922 0.700024)
			(end -0.899922 0.700024)
			(stroke
				(width 0.1)
				(type default)
			)
			(layer "F.Fab")
		)
		(fp_line
			(start 1.35001 -0.225044)
			(end 1.35001 0.175006)
			(stroke
				(width 0.1)
				(type default)
			)
			(layer "F.Fab")
		)
		(fp_line
			(start 1.35001 0.175006)
			(end 0.899922 0.175006)
			(stroke
				(width 0.1)
				(type default)
			)
			(layer "F.Fab")
		)
		(fp_text user "+"
			(at -2.794 0.66675 0)
			(unlocked yes)
			(layer "F.SilkS")
			(effects
				(font
					(size 1.905 1.4224)
					(thickness 0.1524)
				)
				(justify left)
			)
		)
		(fp_text user "-"
			(at 0.762 0.79375 0)
			(unlocked yes)
			(layer "F.SilkS")
			(effects
				(font
					(size 1.905 1.4224)
					(thickness 0.1524)
				)
				(justify left)
			)
		)
		(fp_text user "+"
			(at -2.794 -0.19685 0)
			(unlocked yes)
			(layer "F.Fab")
			(effects
				(font
					(size 1.905 1.4224)
					(thickness 0.1524)
				)
				(justify left)
			)
		)
		(fp_text user "-"
			(at 1.8288 -0.24765 0)
			(unlocked yes)
			(layer "F.Fab")
			(effects
				(font
					(size 1.905 1.4224)
					(thickness 0.1524)
				)
				(justify left)
			)
		)
		(pad "1" smd rect
			(at -1.0922 0 180)
			(size 0.8128 0.8636)
			(layers "F.Cu" "F.Mask" "F.Paste")
			(net "FAN_0_TACH_IL_R")
		)
		(pad "2" smd rect
			(at 1.0922 0)
			(size 0.8128 0.8636)
			(layers "F.Cu" "F.Mask" "F.Paste")
			(net "FAN_0_TACH_IL_D")
		)
	)
	(footprint ""
		(layer "F.Cu")
		(at 17.907 -172.466 180)
		(property "Reference" "R5501"
			(at 0 0 180)
			(layer "F.SilkS")
			(hide yes)
			(effects
				(font
					(size 1.27 1.27)
				)
			)
		)
		(property "Value" ""
			(at 0 0 180)
			(layer "F.Fab")
			(effects
				(font
					(size 1.27 1.27)
				)
			)
		)
		(duplicate_pad_numbers_are_jumpers no)
		(fp_line
			(start 0.7874 0.4064)
			(end -0.7874 0.4064)
			(stroke
				(width 0.1524)
				(type default)
			)
			(layer "F.SilkS")
		)
		(fp_line
			(start 0.7874 -0.4064)
			(end 0.7874 0.4064)
			(stroke
				(width 0.1524)
				(type default)
			)
			(layer "F.SilkS")
		)
		(fp_line
			(start -0.7874 0.4064)
			(end -0.7874 -0.4064)
			(stroke
				(width 0.1524)
				(type default)
			)
			(layer "F.SilkS")
		)
		(fp_line
			(start -0.7874 -0.4064)
			(end 0.7874 -0.4064)
			(stroke
				(width 0.1524)
				(type default)
			)
			(layer "F.SilkS")
		)
		(fp_line
			(start 0.67945 0.3048)
			(end 0.120396 0.3048)
			(stroke
				(width 0.1)
				(type default)
			)
			(layer "F.Fab")
		)
		(fp_line
			(start 0.67945 -0.3048)
			(end 0.67945 0.3048)
			(stroke
				(width 0.1)
				(type default)
			)
			(layer "F.Fab")
		)
		(fp_line
			(start 0.12065 -0.2794)
			(end 0.12065 -0.3048)
			(stroke
				(width 0.1)
				(type default)
			)
			(layer "F.Fab")
		)
		(fp_line
			(start 0.12065 -0.3048)
			(end 0.67945 -0.3048)
			(stroke
				(width 0.1)
				(type default)
			)
			(layer "F.Fab")
		)
		(fp_line
			(start 0.120396 0.3048)
			(end 0.120396 0.2794)
			(stroke
				(width 0.1)
				(type default)
			)
			(layer "F.Fab")
		)
		(fp_line
			(start 0.120396 0.2794)
			(end -0.12065 0.2794)
			(stroke
				(width 0.1)
				(type default)
			)
			(layer "F.Fab")
		)
		(fp_line
			(start -0.12065 0.3048)
			(end -0.67945 0.3048)
			(stroke
				(width 0.1)
				(type default)
			)
			(layer "F.Fab")
		)
		(fp_line
			(start -0.12065 0.2794)
			(end -0.12065 0.3048)
			(stroke
				(width 0.1)
				(type default)
			)
			(layer "F.Fab")
		)
		(fp_line
			(start -0.12065 -0.2794)
			(end 0.12065 -0.2794)
			(stroke
				(width 0.1)
				(type default)
			)
			(layer "F.Fab")
		)
		(fp_line
			(start -0.12065 -0.305054)
			(end -0.12065 -0.2794)
			(stroke
				(width 0.1)
				(type default)
			)
			(layer "F.Fab")
		)
		(fp_line
			(start -0.67945 0.3048)
			(end -0.67945 -0.305054)
			(stroke
				(width 0.1)
				(type default)
			)
			(layer "F.Fab")
		)
		(fp_line
			(start -0.67945 -0.305054)
			(end -0.12065 -0.305054)
			(stroke
				(width 0.1)
				(type default)
			)
			(layer "F.Fab")
		)
		(pad "1" smd circle
			(at -0.40005 0 180)
			(size 0 0)
			(layers "F.Cu" "F.Mask" "F.Paste")
			(net "FAN_6_PRESENT_R_N")
		)
		(pad "2" smd circle
			(at 0.40005 0 180)
			(size 0 0)
			(layers "F.Cu" "F.Mask" "F.Paste")
			(net "FAN_6_PRESENT_N")
		)
	)
	(footprint ""
		(layer "F.Cu")
		(at 25.4 -104.394)
		(property "Reference" "U325"
			(at -1.524 -1.87833 0)
			(unlocked yes)
			(layer "F.SilkS")
			(effects
				(font
					(size 0.7874 0.5842)
					(thickness 0.1524)
				)
				(justify left)
			)
		)
		(property "Value" ""
			(at 0 0 0)
			(layer "F.Fab")
			(effects
				(font
					(size 1.27 1.27)
				)
			)
		)
		(duplicate_pad_numbers_are_jumpers no)
		(fp_line
			(start -1.538478 -1.150874)
			(end -1.538478 1.150874)
			(stroke
				(width 0.1524)
				(type default)
			)
			(layer "F.SilkS")
		)
		(fp_line
			(start -1.538478 1.150874)
			(end 1.538478 1.150874)
			(stroke
				(width 0.1524)
				(type default)
			)
			(layer "F.SilkS")
		)
		(fp_line
			(start 1.538478 -1.150874)
			(end -1.538478 -1.150874)
			(stroke
				(width 0.1524)
				(type default)
			)
			(layer "F.SilkS")
		)
		(fp_line
			(start 1.538478 1.150874)
			(end 1.538478 -1.150874)
			(stroke
				(width 0.1524)
				(type default)
			)
			(layer "F.SilkS")
		)
		(fp_line
			(start -0.674878 -1.100074)
			(end -0.674878 1.100074)
			(stroke
				(width 0.1)
				(type default)
			)
			(layer "F.Fab")
		)
		(fp_line
			(start -0.674878 1.100074)
			(end 0.674878 1.100074)
			(stroke
				(width 0.1)
				(type default)
			)
			(layer "F.Fab")
		)
		(fp_line
			(start 0.674878 -1.100074)
			(end -0.674878 -1.100074)
			(stroke
				(width 0.1)
				(type default)
			)
			(layer "F.Fab")
		)
		(fp_line
			(start 0.674878 1.100074)
			(end 0.674878 -1.100074)
			(stroke
				(width 0.1)
				(type default)
			)
			(layer "F.Fab")
		)
		(pad "1" smd rect
			(at -0.94996 -0.649986 90)
			(size 0.7112 0.9144)
			(layers "F.Cu" "F.Mask" "F.Paste")
			(net "FAN_5_PWM_IL")
		)
		(pad "2" smd rect
			(at -0.94996 0.649986 90)
			(size 0.7112 0.9144)
			(layers "F.Cu" "F.Mask" "F.Paste")
			(net "FAN_5_PWM_OL")
		)
		(pad "3" smd rect
			(at 0.94996 0 90)
			(size 0.7112 0.9144)
			(layers "F.Cu" "F.Mask" "F.Paste")
			(net "FAN_5_PWM_BUF")
		)
	)
)
